(kicad_pcb
	(version 20260206)
	(generator "pcbnew")
	(generator_version "10.0")
	(general
		(thickness 1.6)
		(legacy_teardrops no)
	)
	(paper "A4")
	(title_block
		(title "04192023_DAF0TMB3IC0_F0TG_MB_C_brd_V02_OCP.brd")
		(comment 1 "Grand Teton / footprints 8002-8007 of 8354")
	)
	(layers
		(0 "F.Cu" signal "TOP")
		(4 "In1.Cu" signal "GND")
		(6 "In2.Cu" signal "IN1")
		(8 "In3.Cu" signal "GND1")
		(10 "In4.Cu" signal "IN2")
		(12 "In5.Cu" signal "GND2")
		(14 "In6.Cu" signal "IN3")
		(16 "In7.Cu" signal "GND3")
		(18 "In8.Cu" signal "VCC")
		(20 "In9.Cu" signal "VCC1")
		(22 "In10.Cu" signal "GND4")
		(24 "In11.Cu" signal "IN4")
		(26 "In12.Cu" signal "GND5")
		(28 "In13.Cu" signal "IN5")
		(30 "In14.Cu" signal "GND6")
		(32 "In15.Cu" signal "IN6")
		(34 "In16.Cu" signal "GND7")
		(2 "B.Cu" signal "BOTTOM")
		(9 "F.Adhes" user "F.Adhesive")
		(11 "B.Adhes" user "B.Adhesive")
		(13 "F.Paste" user "Package Geometry/Pastemask Top")
		(15 "B.Paste" user "Package Geometry/Pastemask Bottom")
		(5 "F.SilkS" user "Ref Des/Silkscreen Top")
		(7 "B.SilkS" user "Ref Des/Silkscreen Bottom")
		(1 "F.Mask" user "Board Geometry/Soldermask Top")
		(3 "B.Mask" user "Board Geometry/Soldermask Bottom")
		(17 "Dwgs.User" user "User.Drawings")
		(19 "Cmts.User" user "User.Comments")
		(21 "Eco1.User" user "User.Eco1")
		(23 "Eco2.User" user "User.Eco2")
		(25 "Edge.Cuts" user "Board Geometry/Outline")
		(27 "Margin" user)
		(31 "F.CrtYd" user "Package Geometry/Place Bound Top")
		(29 "B.CrtYd" user "Package Geometry/Place Bound Bottom")
		(35 "F.Fab" user "Ref Des/Assembly Top")
		(33 "B.Fab" user "Ref Des/Assembly Bottom")
	)
	(footprint ""
		(layer "B.Cu")
		(at 355.26599 -417.63696)
		(property "Reference" "Q71"
			(at -1.36906 -2.460244 0)
			(unlocked yes)
			(layer "B.SilkS")
			(effects
				(font
					(size 0.7874 0.5842)
					(thickness 0.1524)
				)
				(justify left mirror)
			)
		)
		(property "Value" ""
			(at 0 0 0)
			(layer "B.Fab")
			(effects
				(font
					(size 1.27 1.27)
				)
				(justify mirror)
			)
		)
		(duplicate_pad_numbers_are_jumpers no)
		(fp_line
			(start -1.332738 -1.100074)
			(end -1.332738 1.100074)
			(stroke
				(width 0.1524)
				(type default)
			)
			(layer "B.SilkS")
		)
		(fp_line
			(start -1.332738 1.100074)
			(end 1.332738 1.100074)
			(stroke
				(width 0.1524)
				(type default)
			)
			(layer "B.SilkS")
		)
		(fp_line
			(start -0.4826 -1.100074)
			(end -1.332738 -1.100074)
			(stroke
				(width 0.1524)
				(type default)
			)
			(layer "B.SilkS")
		)
		(fp_line
			(start 0 -0.541274)
			(end -0.4826 -1.100074)
			(stroke
				(width 0.1524)
				(type default)
			)
			(layer "B.SilkS")
		)
		(fp_line
			(start 0.4826 -1.100074)
			(end 0 -0.541274)
			(stroke
				(width 0.1524)
				(type default)
			)
			(layer "B.SilkS")
		)
		(fp_line
			(start 1.332738 -1.100074)
			(end 0.4826 -1.100074)
			(stroke
				(width 0.1524)
				(type default)
			)
			(layer "B.SilkS")
		)
		(fp_line
			(start 1.332738 1.100074)
			(end 1.332738 -1.100074)
			(stroke
				(width 0.1524)
				(type default)
			)
			(layer "B.SilkS")
		)
		(fp_poly
			(pts
				(xy 0.939038 -1.628648) (xy 1.290066 -2.33045) (xy 0.58801 -2.33045)
			)
			(stroke
				(width 0)
				(type default)
			)
			(fill yes)
			(layer "B.SilkS")
		)
		(fp_line
			(start -0.674878 -1.100074)
			(end -0.674878 1.100074)
			(stroke
				(width 0.1)
				(type default)
			)
			(layer "B.Fab")
		)
		(fp_line
			(start -0.674878 1.100074)
			(end 0.674878 1.100074)
			(stroke
				(width 0.1)
				(type default)
			)
			(layer "B.Fab")
		)
		(fp_line
			(start 0.674878 -1.100074)
			(end -0.674878 -1.100074)
			(stroke
				(width 0.1)
				(type default)
			)
			(layer "B.Fab")
		)
		(fp_line
			(start 0.674878 1.100074)
			(end 0.674878 -1.100074)
			(stroke
				(width 0.1)
				(type default)
			)
			(layer "B.Fab")
		)
		(fp_poly
			(pts
				(xy 2.2352 -0.298958) (xy 2.2352 -1.001014) (xy 1.533144 -0.649986)
			)
			(stroke
				(width 0)
				(type default)
			)
			(fill yes)
			(layer "B.Fab")
		)
		(pad "1" smd rect
			(at 0.94996 -0.649986 90)
			(size 0.4318 0.508)
			(layers "B.Cu" "B.Mask" "B.Paste")
			(net "GND")
		)
		(pad "2" smd rect
			(at 0.94996 0 90)
			(size 0.4318 0.508)
			(layers "B.Cu" "B.Mask" "B.Paste")
			(net "FM_SWB_PWRGD")
		)
		(pad "3" smd rect
			(at 0.94996 0.649986 90)
			(size 0.4318 0.508)
			(layers "B.Cu" "B.Mask" "B.Paste")
			(net "FM_SWB_PWRGD_ISO")
		)
		(pad "4" smd rect
			(at -0.94996 0.649986 90)
			(size 0.4318 0.508)
			(layers "B.Cu" "B.Mask" "B.Paste")
			(net "GND")
		)
		(pad "5" smd rect
			(at -0.94996 0 90)
			(size 0.4318 0.508)
			(layers "B.Cu" "B.Mask" "B.Paste")
			(net "FM_SWB_PWRGD_N")
		)
		(pad "6" smd rect
			(at -0.94996 -0.649986 90)
			(size 0.4318 0.508)
			(layers "B.Cu" "B.Mask" "B.Paste")
			(net "FM_SWB_PWRGD_N")
		)
	)
	(footprint ""
		(layer "B.Cu")
		(at 301.535338 -424.449748 -90)
		(property "Reference" "R1410"
			(at 0 0 90)
			(layer "B.SilkS")
			(hide yes)
			(effects
				(font
					(size 1.27 1.27)
				)
				(justify mirror)
			)
		)
		(property "Value" ""
			(at 0 0 90)
			(layer "B.Fab")
			(effects
				(font
					(size 1.27 1.27)
				)
				(justify mirror)
			)
		)
		(duplicate_pad_numbers_are_jumpers no)
		(fp_line
			(start -0.32512 0.175006)
			(end 0.32512 0.175006)
			(stroke
				(width 0.1)
				(type default)
			)
			(layer "B.Fab")
		)
		(fp_line
			(start 0.32512 0.175006)
			(end 0.32512 -0.175006)
			(stroke
				(width 0.1)
				(type default)
			)
			(layer "B.Fab")
		)
		(fp_line
			(start -0.32512 -0.175006)
			(end -0.32512 0.175006)
			(stroke
				(width 0.1)
				(type default)
			)
			(layer "B.Fab")
		)
		(fp_line
			(start 0.32512 -0.175006)
			(end -0.32512 -0.175006)
			(stroke
				(width 0.1)
				(type default)
			)
			(layer "B.Fab")
		)
		(pad "1" smd rect
			(at 0.2667 0 90)
			(size 0.3048 0.381)
			(layers "B.Cu" "B.Mask" "B.Paste")
			(net "P1V8_CPU0_RT_1D")
		)
		(pad "2" smd rect
			(at -0.2667 0 270)
			(size 0.3048 0.381)
			(layers "B.Cu" "B.Mask" "B.Paste")
			(net "SMB_RT_CPU0_P0_ROM_MUX_1D_SDA")
		)
	)
	(footprint ""
		(layer "B.Cu")
		(at 100.881434 -252.599952 180)
		(property "Reference" "C2665"
			(at 0 0 0)
			(layer "B.SilkS")
			(hide yes)
			(effects
				(font
					(size 1.27 1.27)
				)
				(justify mirror)
			)
		)
		(property "Value" ""
			(at 0 0 0)
			(layer "B.Fab")
			(effects
				(font
					(size 1.27 1.27)
				)
				(justify mirror)
			)
		)
		(duplicate_pad_numbers_are_jumpers no)
		(fp_line
			(start 0.7874 0.4064)
			(end 0.7874 -0.4064)
			(stroke
				(width 0.1524)
				(type default)
			)
			(layer "B.SilkS")
		)
		(fp_line
			(start 0.7874 -0.4064)
			(end -0.7874 -0.4064)
			(stroke
				(width 0.1524)
				(type default)
			)
			(layer "B.SilkS")
		)
		(fp_line
			(start -0.7874 0.4064)
			(end 0.7874 0.4064)
			(stroke
				(width 0.1524)
				(type default)
			)
			(layer "B.SilkS")
		)
		(fp_line
			(start -0.7874 -0.4064)
			(end -0.7874 0.4064)
			(stroke
				(width 0.1524)
				(type default)
			)
			(layer "B.SilkS")
		)
		(fp_line
			(start 0.67945 0.3048)
			(end 0.67945 -0.305054)
			(stroke
				(width 0.1)
				(type default)
			)
			(layer "B.Fab")
		)
		(fp_line
			(start 0.67945 -0.305054)
			(end 0.12065 -0.305054)
			(stroke
				(width 0.1)
				(type default)
			)
			(layer "B.Fab")
		)
		(fp_line
			(start 0.12065 0.3048)
			(end 0.67945 0.3048)
			(stroke
				(width 0.1)
				(type default)
			)
			(layer "B.Fab")
		)
		(fp_line
			(start 0.12065 0.2794)
			(end 0.12065 0.3048)
			(stroke
				(width 0.1)
				(type default)
			)
			(layer "B.Fab")
		)
		(fp_line
			(start 0.12065 -0.2794)
			(end -0.12065 -0.2794)
			(stroke
				(width 0.1)
				(type default)
			)
			(layer "B.Fab")
		)
		(fp_line
			(start 0.12065 -0.305054)
			(end 0.12065 -0.2794)
			(stroke
				(width 0.1)
				(type default)
			)
			(layer "B.Fab")
		)
		(fp_line
			(start -0.120396 0.3048)
			(end -0.120396 0.2794)
			(stroke
				(width 0.1)
				(type default)
			)
			(layer "B.Fab")
		)
		(fp_line
			(start -0.120396 0.2794)
			(end 0.12065 0.2794)
			(stroke
				(width 0.1)
				(type default)
			)
			(layer "B.Fab")
		)
		(fp_line
			(start -0.12065 -0.2794)
			(end -0.12065 -0.3048)
			(stroke
				(width 0.1)
				(type default)
			)
			(layer "B.Fab")
		)
		(fp_line
			(start -0.12065 -0.3048)
			(end -0.67945 -0.3048)
			(stroke
				(width 0.1)
				(type default)
			)
			(layer "B.Fab")
		)
		(fp_line
			(start -0.67945 0.3048)
			(end -0.120396 0.3048)
			(stroke
				(width 0.1)
				(type default)
			)
			(layer "B.Fab")
		)
		(fp_line
			(start -0.67945 -0.3048)
			(end -0.67945 0.3048)
			(stroke
				(width 0.1)
				(type default)
			)
			(layer "B.Fab")
		)
		(pad "1" smd circle
			(at 0.40005 0)
			(size 0 0)
			(layers "B.Cu" "B.Mask" "B.Paste")
			(net "PVDD18_S5_P1")
		)
		(pad "2" smd circle
			(at -0.40005 0)
			(size 0 0)
			(layers "B.Cu" "B.Mask" "B.Paste")
			(net "GND")
		)
	)
	(footprint ""
		(layer "B.Cu")
		(at 326.815958 -202.113896 90)
		(property "Reference" "R414"
			(at 0 0 90)
			(layer "B.SilkS")
			(hide yes)
			(effects
				(font
					(size 1.27 1.27)
				)
				(justify mirror)
			)
		)
		(property "Value" ""
			(at 0 0 90)
			(layer "B.Fab")
			(effects
				(font
					(size 1.27 1.27)
				)
				(justify mirror)
			)
		)
		(duplicate_pad_numbers_are_jumpers no)
		(fp_line
			(start 0.7874 -0.4064)
			(end -0.7874 -0.4064)
			(stroke
				(width 0.1524)
				(type default)
			)
			(layer "B.SilkS")
		)
		(fp_line
			(start -0.7874 -0.4064)
			(end -0.7874 0.4064)
			(stroke
				(width 0.1524)
				(type default)
			)
			(layer "B.SilkS")
		)
		(fp_line
			(start 0.7874 0.4064)
			(end 0.7874 -0.4064)
			(stroke
				(width 0.1524)
				(type default)
			)
			(layer "B.SilkS")
		)
		(fp_line
			(start -0.7874 0.4064)
			(end 0.7874 0.4064)
			(stroke
				(width 0.1524)
				(type default)
			)
			(layer "B.SilkS")
		)
		(fp_line
			(start 0.67945 -0.305054)
			(end 0.12065 -0.305054)
			(stroke
				(width 0.1)
				(type default)
			)
			(layer "B.Fab")
		)
		(fp_line
			(start 0.12065 -0.305054)
			(end 0.12065 -0.2794)
			(stroke
				(width 0.1)
				(type default)
			)
			(layer "B.Fab")
		)
		(fp_line
			(start -0.12065 -0.3048)
			(end -0.67945 -0.3048)
			(stroke
				(width 0.1)
				(type default)
			)
			(layer "B.Fab")
		)
		(fp_line
			(start -0.67945 -0.3048)
			(end -0.67945 0.3048)
			(stroke
				(width 0.1)
				(type default)
			)
			(layer "B.Fab")
		)
		(fp_line
			(start 0.12065 -0.2794)
			(end -0.12065 -0.2794)
			(stroke
				(width 0.1)
				(type default)
			)
			(layer "B.Fab")
		)
		(fp_line
			(start -0.12065 -0.2794)
			(end -0.12065 -0.3048)
			(stroke
				(width 0.1)
				(type default)
			)
			(layer "B.Fab")
		)
		(fp_line
			(start 0.12065 0.2794)
			(end 0.12065 0.3048)
			(stroke
				(width 0.1)
				(type default)
			)
			(layer "B.Fab")
		)
		(fp_line
			(start -0.120396 0.2794)
			(end 0.12065 0.2794)
			(stroke
				(width 0.1)
				(type default)
			)
			(layer "B.Fab")
		)
		(fp_line
			(start 0.67945 0.3048)
			(end 0.67945 -0.305054)
			(stroke
				(width 0.1)
				(type default)
			)
			(layer "B.Fab")
		)
		(fp_line
			(start 0.12065 0.3048)
			(end 0.67945 0.3048)
			(stroke
				(width 0.1)
				(type default)
			)
			(layer "B.Fab")
		)
		(fp_line
			(start -0.120396 0.3048)
			(end -0.120396 0.2794)
			(stroke
				(width 0.1)
				(type default)
			)
			(layer "B.Fab")
		)
		(fp_line
			(start -0.67945 0.3048)
			(end -0.120396 0.3048)
			(stroke
				(width 0.1)
				(type default)
			)
			(layer "B.Fab")
		)
		(pad "1" smd circle
			(at 0.40005 0 270)
			(size 0 0)
			(layers "B.Cu" "B.Mask" "B.Paste")
			(net "CPU0_XTRIG_L5")
		)
		(pad "2" smd circle
			(at -0.40005 0 270)
			(size 0 0)
			(layers "B.Cu" "B.Mask" "B.Paste")
			(net "PVDD18_S5_P0")
		)
	)
	(footprint ""
		(layer "B.Cu")
		(at 235.1151 -215.186514)
		(property "Reference" "R256"
			(at 0 0 0)
			(layer "B.SilkS")
			(hide yes)
			(effects
				(font
					(size 1.27 1.27)
				)
				(justify mirror)
			)
		)
		(property "Value" ""
			(at 0 0 0)
			(layer "B.Fab")
			(effects
				(font
					(size 1.27 1.27)
				)
				(justify mirror)
			)
		)
		(duplicate_pad_numbers_are_jumpers no)
		(fp_line
			(start -0.7874 -0.4064)
			(end -0.7874 0.4064)
			(stroke
				(width 0.1524)
				(type default)
			)
			(layer "B.SilkS")
		)
		(fp_line
			(start -0.7874 0.4064)
			(end 0.7874 0.4064)
			(stroke
				(width 0.1524)
				(type default)
			)
			(layer "B.SilkS")
		)
		(fp_line
			(start 0.7874 -0.4064)
			(end -0.7874 -0.4064)
			(stroke
				(width 0.1524)
				(type default)
			)
			(layer "B.SilkS")
		)
		(fp_line
			(start 0.7874 0.4064)
			(end 0.7874 -0.4064)
			(stroke
				(width 0.1524)
				(type default)
			)
			(layer "B.SilkS")
		)
		(fp_line
			(start -0.67945 -0.3048)
			(end -0.67945 0.3048)
			(stroke
				(width 0.1)
				(type default)
			)
			(layer "B.Fab")
		)
		(fp_line
			(start -0.67945 0.3048)
			(end -0.120396 0.3048)
			(stroke
				(width 0.1)
				(type default)
			)
			(layer "B.Fab")
		)
		(fp_line
			(start -0.12065 -0.3048)
			(end -0.67945 -0.3048)
			(stroke
				(width 0.1)
				(type default)
			)
			(layer "B.Fab")
		)
		(fp_line
			(start -0.12065 -0.2794)
			(end -0.12065 -0.3048)
			(stroke
				(width 0.1)
				(type default)
			)
			(layer "B.Fab")
		)
		(fp_line
			(start -0.120396 0.2794)
			(end 0.12065 0.2794)
			(stroke
				(width 0.1)
				(type default)
			)
			(layer "B.Fab")
		)
		(fp_line
			(start -0.120396 0.3048)
			(end -0.120396 0.2794)
			(stroke
				(width 0.1)
				(type default)
			)
			(layer "B.Fab")
		)
		(fp_line
			(start 0.12065 -0.305054)
			(end 0.12065 -0.2794)
			(stroke
				(width 0.1)
				(type default)
			)
			(layer "B.Fab")
		)
		(fp_line
			(start 0.12065 -0.2794)
			(end -0.12065 -0.2794)
			(stroke
				(width 0.1)
				(type default)
			)
			(layer "B.Fab")
		)
		(fp_line
			(start 0.12065 0.2794)
			(end 0.12065 0.3048)
			(stroke
				(width 0.1)
				(type default)
			)
			(layer "B.Fab")
		)
		(fp_line
			(start 0.12065 0.3048)
			(end 0.67945 0.3048)
			(stroke
				(width 0.1)
				(type default)
			)
			(layer "B.Fab")
		)
		(fp_line
			(start 0.67945 -0.305054)
			(end 0.12065 -0.305054)
			(stroke
				(width 0.1)
				(type default)
			)
			(layer "B.Fab")
		)
		(fp_line
			(start 0.67945 0.3048)
			(end 0.67945 -0.305054)
			(stroke
				(width 0.1)
				(type default)
			)
			(layer "B.Fab")
		)
		(pad "1" smd rect
			(at 0.40005 0)
			(size 0.4572 0.508)
			(layers "B.Cu" "B.Mask" "B.Paste")
			(net "SMB_CPU0_CPU1_APML_BUF1_SCL_R2")
		)
		(pad "2" smd rect
			(at -0.40005 0)
			(size 0.4572 0.508)
			(layers "B.Cu" "B.Mask" "B.Paste")
			(net "SMB_CPU0_CPU1_APML_SCL_R2")
		)
	)
	(footprint ""
		(layer "B.Cu")
		(at 208.56448 -35.804348 90)
		(property "Reference" "C2019"
			(at 0 0 90)
			(layer "B.SilkS")
			(hide yes)
			(effects
				(font
					(size 1.27 1.27)
				)
				(justify mirror)
			)
		)
		(property "Value" ""
			(at 0 0 90)
			(layer "B.Fab")
			(effects
				(font
					(size 1.27 1.27)
				)
				(justify mirror)
			)
		)
		(duplicate_pad_numbers_are_jumpers no)
		(fp_line
			(start 0.7874 -0.4064)
			(end -0.7874 -0.4064)
			(stroke
				(width 0.1524)
				(type default)
			)
			(layer "B.SilkS")
		)
		(fp_line
			(start -0.7874 -0.4064)
			(end -0.7874 0.4064)
			(stroke
				(width 0.1524)
				(type default)
			)
			(layer "B.SilkS")
		)
		(fp_line
			(start 0.7874 0.4064)
			(end 0.7874 -0.4064)
			(stroke
				(width 0.1524)
				(type default)
			)
			(layer "B.SilkS")
		)
		(fp_line
			(start -0.7874 0.4064)
			(end 0.7874 0.4064)
			(stroke
				(width 0.1524)
				(type default)
			)
			(layer "B.SilkS")
		)
		(fp_line
			(start 0.67945 -0.305054)
			(end 0.12065 -0.305054)
			(stroke
				(width 0.1)
				(type default)
			)
			(layer "B.Fab")
		)
		(fp_line
			(start 0.12065 -0.305054)
			(end 0.12065 -0.2794)
			(stroke
				(width 0.1)
				(type default)
			)
			(layer "B.Fab")
		)
		(fp_line
			(start -0.12065 -0.3048)
			(end -0.67945 -0.3048)
			(stroke
				(width 0.1)
				(type default)
			)
			(layer "B.Fab")
		)
		(fp_line
			(start -0.67945 -0.3048)
			(end -0.67945 0.3048)
			(stroke
				(width 0.1)
				(type default)
			)
			(layer "B.Fab")
		)
		(fp_line
			(start 0.12065 -0.2794)
			(end -0.12065 -0.2794)
			(stroke
				(width 0.1)
				(type default)
			)
			(layer "B.Fab")
		)
		(fp_line
			(start -0.12065 -0.2794)
			(end -0.12065 -0.3048)
			(stroke
				(width 0.1)
				(type default)
			)
			(layer "B.Fab")
		)
		(fp_line
			(start 0.12065 0.2794)
			(end 0.12065 0.3048)
			(stroke
				(width 0.1)
				(type default)
			)
			(layer "B.Fab")
		)
		(fp_line
			(start -0.120396 0.2794)
			(end 0.12065 0.2794)
			(stroke
				(width 0.1)
				(type default)
			)
			(layer "B.Fab")
		)
		(fp_line
			(start 0.67945 0.3048)
			(end 0.67945 -0.305054)
			(stroke
				(width 0.1)
				(type default)
			)
			(layer "B.Fab")
		)
		(fp_line
			(start 0.12065 0.3048)
			(end 0.67945 0.3048)
			(stroke
				(width 0.1)
				(type default)
			)
			(layer "B.Fab")
		)
		(fp_line
			(start -0.120396 0.3048)
			(end -0.120396 0.2794)
			(stroke
				(width 0.1)
				(type default)
			)
			(layer "B.Fab")
		)
		(fp_line
			(start -0.67945 0.3048)
			(end -0.120396 0.3048)
			(stroke
				(width 0.1)
				(type default)
			)
			(layer "B.Fab")
		)
		(pad "1" smd circle
			(at 0.40005 0 270)
			(size 0 0)
			(layers "B.Cu" "B.Mask" "B.Paste")
			(net "P12V_SCM_R")
		)
		(pad "2" smd circle
			(at -0.40005 0 270)
			(size 0 0)
			(layers "B.Cu" "B.Mask" "B.Paste")
			(net "GND")
		)
	)
)
